(kicad_pcb
	(version 20260206)
	(generator "pcbnew")
	(generator_version "10.0")
	(general
		(thickness 1.6)
		(legacy_teardrops no)
	)
	(paper "A4")
	(title_block
		(title "Bryce Canyon_IOM_IOC_16318-2_OCP.brd")
		(comment 1 "Bryce Canyon / footprints 465-471 of 1605")
	)
	(layers
		(0 "F.Cu" signal "TOP")
		(4 "In1.Cu" signal "L2GND")
		(6 "In2.Cu" signal "L3")
		(8 "In3.Cu" signal "L4VCC")
		(10 "In4.Cu" signal "L5VCC")
		(12 "In5.Cu" signal "L6")
		(14 "In6.Cu" signal "L7GND")
		(2 "B.Cu" signal "BOTTOM")
		(9 "F.Adhes" user "F.Adhesive")
		(11 "B.Adhes" user "B.Adhesive")
		(13 "F.Paste" user "Package Geometry/Pastemask Top")
		(15 "B.Paste" user "Package Geometry/Pastemask Bottom")
		(5 "F.SilkS" user "Ref Des/Silkscreen Top")
		(7 "B.SilkS" user "Ref Des/Silkscreen Bottom")
		(1 "F.Mask" user "Board Geometry/Soldermask Top")
		(3 "B.Mask" user "Board Geometry/Soldermask Bottom")
		(17 "Dwgs.User" user "User.Drawings")
		(19 "Cmts.User" user "User.Comments")
		(21 "Eco1.User" user "User.Eco1")
		(23 "Eco2.User" user "User.Eco2")
		(25 "Edge.Cuts" user "Board Geometry/Outline")
		(27 "Margin" user)
		(31 "F.CrtYd" user "Package Geometry/Place Bound Top")
		(29 "B.CrtYd" user "Package Geometry/Place Bound Bottom")
		(35 "F.Fab" user "Ref Des/Assembly Top")
		(33 "B.Fab" user "Ref Des/Assembly Bottom")
	)
	(footprint ""
		(layer "F.Cu")
		(at 93.668088 -61.133736 90)
		(property "Reference" "R704"
			(at 0 0 90)
			(layer "F.SilkS")
			(hide yes)
			(effects
				(font
					(size 1.27 1.27)
				)
			)
		)
		(property "Value" "100KR2J-4-GP"
			(at 0.064008 -3.993896 90)
			(unlocked yes)
			(layer "F.Fab")
			(hide yes)
			(effects
				(font
					(size 1.016 1.016)
					(thickness 0.1524)
				)
			)
		)
		(property "Device Type" "R402H15"
			(at 0.064008 -5.517896 90)
			(unlocked yes)
			(layer "F.Fab")
			(hide yes)
			(effects
				(font
					(size 1.016 1.016)
					(thickness 0.1524)
				)
			)
		)
		(duplicate_pad_numbers_are_jumpers no)
		(fp_line
			(start 0.508 -0.9398)
			(end -0.508 -0.9398)
			(stroke
				(width 0.1524)
				(type default)
			)
			(layer "F.SilkS")
		)
		(fp_line
			(start -0.508 -0.9398)
			(end -0.508 0.9398)
			(stroke
				(width 0.1524)
				(type default)
			)
			(layer "F.SilkS")
		)
		(fp_rect
			(start -0.508 0.9398)
			(end 0.508 -0.9398)
			(stroke
				(width 0)
				(type default)
			)
			(fill no)
			(layer "F.CrtYd")
		)
		(fp_rect
			(start -0.508 0.9398)
			(end 0.508 -0.9398)
			(stroke
				(width 0)
				(type default)
			)
			(fill no)
			(layer "F.Fab")
		)
		(pad "1" smd custom
			(at 0 -0.4445 90)
			(size 0.1397 0.1397)
			(layers "F.Cu" "F.Mask" "F.Paste")
			(net "GND")
			(options
				(clearance outline)
				(anchor circle)
			)
			(primitives
				(gr_poly
					(pts
						(arc
							(start -0.1778 -0.2794)
							(mid -0.249642 -0.249642)
							(end -0.2794 -0.1778)
						)
						(arc
							(start -0.2794 0.1778)
							(mid -0.249642 0.249642)
							(end -0.1778 0.2794)
						)
						(arc
							(start 0.1778 0.2794)
							(mid 0.249642 0.249642)
							(end 0.2794 0.1778)
						)
						(arc
							(start 0.2794 -0.1778)
							(mid 0.249642 -0.249642)
							(end 0.1778 -0.2794)
						)
					)
					(width 0)
					(fill yes)
				)
			)
		)
		(pad "2" smd custom
			(at 0 0.4445 90)
			(size 0.1397 0.1397)
			(layers "F.Cu" "F.Mask" "F.Paste")
			(net "IOM_FULL_PWR_EN")
			(options
				(clearance outline)
				(anchor circle)
			)
			(primitives
				(gr_poly
					(pts
						(arc
							(start -0.1778 -0.2794)
							(mid -0.249642 -0.249642)
							(end -0.2794 -0.1778)
						)
						(arc
							(start -0.2794 0.1778)
							(mid -0.249642 0.249642)
							(end -0.1778 0.2794)
						)
						(arc
							(start 0.1778 0.2794)
							(mid 0.249642 0.249642)
							(end 0.2794 0.1778)
						)
						(arc
							(start 0.2794 -0.1778)
							(mid 0.249642 -0.249642)
							(end 0.1778 -0.2794)
						)
					)
					(width 0)
					(fill yes)
				)
			)
		)
	)
	(footprint ""
		(layer "F.Cu")
		(at 206.616046 -17.357344 180)
		(property "Reference" "R614"
			(at 0 0 180)
			(layer "F.SilkS")
			(hide yes)
			(effects
				(font
					(size 1.27 1.27)
				)
			)
		)
		(property "Value" "0R2J-2-GP"
			(at 0.064008 -3.993896 180)
			(unlocked yes)
			(layer "F.Fab")
			(hide yes)
			(effects
				(font
					(size 1.016 1.016)
					(thickness 0.1524)
				)
			)
		)
		(property "Device Type" "R402H16"
			(at 0.064008 -5.517896 180)
			(unlocked yes)
			(layer "F.Fab")
			(hide yes)
			(effects
				(font
					(size 1.016 1.016)
					(thickness 0.1524)
				)
			)
		)
		(duplicate_pad_numbers_are_jumpers no)
		(fp_line
			(start 0.508 -0.9398)
			(end -0.508 -0.9398)
			(stroke
				(width 0.1524)
				(type default)
			)
			(layer "F.SilkS")
		)
		(fp_line
			(start -0.508 -0.9398)
			(end -0.508 0.9398)
			(stroke
				(width 0.1524)
				(type default)
			)
			(layer "F.SilkS")
		)
		(fp_rect
			(start -0.508 0.9398)
			(end 0.508 -0.9398)
			(stroke
				(width 0)
				(type default)
			)
			(fill no)
			(layer "F.CrtYd")
		)
		(fp_rect
			(start -0.508 0.9398)
			(end 0.508 -0.9398)
			(stroke
				(width 0)
				(type default)
			)
			(fill no)
			(layer "F.Fab")
		)
		(pad "1" smd custom
			(at 0 -0.4445 180)
			(size 0.1397 0.1397)
			(layers "F.Cu" "F.Mask" "F.Paste")
			(net "BMC_ML_PWR_BLUE_LED_R")
			(options
				(clearance outline)
				(anchor circle)
			)
			(primitives
				(gr_poly
					(pts
						(arc
							(start -0.1778 -0.2794)
							(mid -0.249642 -0.249642)
							(end -0.2794 -0.1778)
						)
						(arc
							(start -0.2794 0.1778)
							(mid -0.249642 0.249642)
							(end -0.1778 0.2794)
						)
						(arc
							(start 0.1778 0.2794)
							(mid 0.249642 0.249642)
							(end 0.2794 0.1778)
						)
						(arc
							(start 0.2794 -0.1778)
							(mid 0.249642 -0.249642)
							(end 0.1778 -0.2794)
						)
					)
					(width 0)
					(fill yes)
				)
			)
		)
		(pad "2" smd custom
			(at 0 0.4445 180)
			(size 0.1397 0.1397)
			(layers "F.Cu" "F.Mask" "F.Paste")
			(net "BMC_ML_PWR_BLUE_LED")
			(options
				(clearance outline)
				(anchor circle)
			)
			(primitives
				(gr_poly
					(pts
						(arc
							(start -0.1778 -0.2794)
							(mid -0.249642 -0.249642)
							(end -0.2794 -0.1778)
						)
						(arc
							(start -0.2794 0.1778)
							(mid -0.249642 0.249642)
							(end -0.1778 0.2794)
						)
						(arc
							(start 0.1778 0.2794)
							(mid 0.249642 0.249642)
							(end 0.2794 0.1778)
						)
						(arc
							(start 0.2794 -0.1778)
							(mid 0.249642 -0.249642)
							(end 0.1778 -0.2794)
						)
					)
					(width 0)
					(fill yes)
				)
			)
		)
	)
	(footprint ""
		(layer "F.Cu")
		(at 206.5401 -132.957316 180)
		(property "Reference" "C256"
			(at 0 0 180)
			(layer "F.SilkS")
			(hide yes)
			(effects
				(font
					(size 1.27 1.27)
				)
			)
		)
		(property "Value" "SC10U6D3V5KX-4GP"
			(at -0.0762 -6.1214 180)
			(unlocked yes)
			(layer "F.Fab")
			(hide yes)
			(effects
				(font
					(size 1.016 1.016)
					(thickness 0.1524)
				)
			)
		)
		(property "Device Type" "C805H58"
			(at -0.0762 -8.1534 180)
			(unlocked yes)
			(layer "F.Fab")
			(hide yes)
			(effects
				(font
					(size 1.016 1.016)
					(thickness 0.1524)
				)
			)
		)
		(duplicate_pad_numbers_are_jumpers no)
		(fp_line
			(start 0.635 0)
			(end -0.635 0)
			(stroke
				(width 0.508)
				(type default)
			)
			(layer "F.SilkS")
		)
		(fp_rect
			(start -0.9652 1.778)
			(end 0.9652 -1.778)
			(stroke
				(width 0)
				(type default)
			)
			(fill no)
			(layer "F.CrtYd")
		)
		(fp_poly
			(pts
				(xy -0.9652 -1.778) (xy 0.9652 -1.778) (xy 0.9652 1.778) (xy -0.9652 1.778)
			)
			(stroke
				(width 0)
				(type default)
			)
			(fill no)
			(layer "F.Fab")
		)
		(pad "1" smd rect
			(at 0 -0.9652 180)
			(size 1.397 1.143)
			(layers "F.Cu" "F.Mask" "F.Paste")
			(net "P1V8_STBY")
		)
		(pad "2" smd rect
			(at 0 0.9652 180)
			(size 1.397 1.143)
			(layers "F.Cu" "F.Mask" "F.Paste")
			(net "GND")
		)
	)
	(footprint ""
		(layer "F.Cu")
		(at 194.005454 -124.591826 180)
		(property "Reference" "C279"
			(at 0 0 180)
			(layer "F.SilkS")
			(hide yes)
			(effects
				(font
					(size 1.27 1.27)
				)
			)
		)
		(property "Value" "SC6K8P50V2KX-GP"
			(at 1.1811 -2.7051 180)
			(unlocked yes)
			(layer "F.Fab")
			(hide yes)
			(effects
				(font
					(size 1.016 1.016)
					(thickness 0.1524)
				)
			)
		)
		(property "Device Type" "C402H22"
			(at 1.1811 -4.2291 180)
			(unlocked yes)
			(layer "F.Fab")
			(hide yes)
			(effects
				(font
					(size 1.016 1.016)
					(thickness 0.1524)
				)
			)
		)
		(duplicate_pad_numbers_are_jumpers no)
		(fp_rect
			(start -0.4318 0.9525)
			(end 0.4318 -0.9525)
			(stroke
				(width 0)
				(type default)
			)
			(fill no)
			(layer "F.CrtYd")
		)
		(fp_rect
			(start -0.4318 0.9525)
			(end 0.4318 -0.9525)
			(stroke
				(width 0)
				(type default)
			)
			(fill no)
			(layer "F.Fab")
		)
		(pad "1" smd custom
			(at 0 -0.4445 180)
			(size 0.1524 0.1524)
			(layers "F.Cu" "F.Mask" "F.Paste")
			(net "VT235_VFB")
			(options
				(clearance outline)
				(anchor circle)
			)
			(primitives
				(gr_poly
					(pts
						(arc
							(start 0.3048 -0.2032)
							(mid 0.275042 -0.275042)
							(end 0.2032 -0.3048)
						)
						(arc
							(start -0.2032 -0.3048)
							(mid -0.275042 -0.275042)
							(end -0.3048 -0.2032)
						)
						(arc
							(start -0.3048 0.2032)
							(mid -0.275042 0.275042)
							(end -0.2032 0.3048)
						)
						(arc
							(start 0.2032 0.3048)
							(mid 0.275042 0.275042)
							(end 0.3048 0.2032)
						)
					)
					(width 0)
					(fill yes)
				)
			)
		)
		(pad "2" smd custom
			(at 0 0.4445 180)
			(size 0.1524 0.1524)
			(layers "F.Cu" "F.Mask" "F.Paste")
			(net "VT235_VDES")
			(options
				(clearance outline)
				(anchor circle)
			)
			(primitives
				(gr_poly
					(pts
						(arc
							(start 0.3048 -0.2032)
							(mid 0.275042 -0.275042)
							(end 0.2032 -0.3048)
						)
						(arc
							(start -0.2032 -0.3048)
							(mid -0.275042 -0.275042)
							(end -0.3048 -0.2032)
						)
						(arc
							(start -0.3048 0.2032)
							(mid -0.275042 0.275042)
							(end -0.2032 0.3048)
						)
						(arc
							(start 0.2032 0.3048)
							(mid 0.275042 0.275042)
							(end 0.3048 0.2032)
						)
					)
					(width 0)
					(fill yes)
				)
			)
		)
	)
	(footprint ""
		(layer "F.Cu")
		(at 142.113 -18.415)
		(property "Reference" "Q22"
			(at 0 0 0)
			(layer "F.SilkS")
			(hide yes)
			(effects
				(font
					(size 1.27 1.27)
				)
			)
		)
		(property "Value" "SSM3K324R-GP"
			(at 0.127 -8.9662 0)
			(unlocked yes)
			(layer "F.Fab")
			(hide yes)
			(effects
				(font
					(size 1.016 1.016)
					(thickness 0.1524)
				)
			)
		)
		(property "Device Type" "SOT23DGS2D4H35"
			(at 0.127 -10.4902 0)
			(unlocked yes)
			(layer "F.Fab")
			(hide yes)
			(effects
				(font
					(size 1.016 1.016)
					(thickness 0.1524)
				)
			)
		)
		(duplicate_pad_numbers_are_jumpers no)
		(fp_line
			(start -1.651 -1.778)
			(end -1.651 1.778)
			(stroke
				(width 0.1524)
				(type default)
			)
			(layer "F.SilkS")
		)
		(fp_line
			(start -1.651 1.778)
			(end 1.651 1.778)
			(stroke
				(width 0.1524)
				(type default)
			)
			(layer "F.SilkS")
		)
		(fp_line
			(start 1.651 -1.778)
			(end -1.651 -1.778)
			(stroke
				(width 0.1524)
				(type default)
			)
			(layer "F.SilkS")
		)
		(fp_line
			(start 1.651 1.778)
			(end 1.651 -1.778)
			(stroke
				(width 0.1524)
				(type default)
			)
			(layer "F.SilkS")
		)
		(fp_poly
			(pts
				(xy -1.778 1.8796) (xy -1.778 -1.8796) (xy 1.778 -1.8796) (xy 1.778 1.8796)
			)
			(stroke
				(width 0)
				(type default)
			)
			(fill no)
			(layer "F.CrtYd")
		)
		(fp_poly
			(pts
				(xy -1.778 1.8796) (xy -1.778 -1.8796) (xy 1.778 -1.8796) (xy 1.778 1.8796)
			)
			(stroke
				(width 0)
				(type default)
			)
			(fill no)
			(layer "F.Fab")
		)
		(pad "D" smd custom
			(at 0 -0.9525)
			(size 0.1905 0.1905)
			(layers "F.Cu" "F.Mask" "F.Paste")
			(net "EXT2_LED_YELLOW_D")
			(options
				(clearance outline)
				(anchor circle)
			)
			(primitives
				(gr_poly
					(pts
						(arc
							(start -0.1778 0.5715)
							(mid -0.321484 0.511984)
							(end -0.381 0.3683)
						)
						(arc
							(start -0.381 -0.3683)
							(mid -0.321484 -0.511984)
							(end -0.1778 -0.5715)
						)
						(arc
							(start 0.1778 -0.5715)
							(mid 0.321484 -0.511984)
							(end 0.381 -0.3683)
						)
						(arc
							(start 0.381 0.3683)
							(mid 0.321484 0.511984)
							(end 0.1778 0.5715)
						)
					)
					(width 0)
					(fill yes)
				)
			)
		)
		(pad "G" smd custom
			(at -0.98425 0.9525)
			(size 0.1905 0.1905)
			(layers "F.Cu" "F.Mask" "F.Paste")
			(net "IOC_EXT2_LED_Y_XOR")
			(options
				(clearance outline)
				(anchor circle)
			)
			(primitives
				(gr_poly
					(pts
						(arc
							(start -0.1778 0.5715)
							(mid -0.321484 0.511984)
							(end -0.381 0.3683)
						)
						(arc
							(start -0.381 -0.3683)
							(mid -0.321484 -0.511984)
							(end -0.1778 -0.5715)
						)
						(arc
							(start 0.1778 -0.5715)
							(mid 0.321484 -0.511984)
							(end 0.381 -0.3683)
						)
						(arc
							(start 0.381 0.3683)
							(mid 0.321484 0.511984)
							(end 0.1778 0.5715)
						)
					)
					(width 0)
					(fill yes)
				)
			)
		)
		(pad "S" smd custom
			(at 0.98425 0.9525)
			(size 0.1905 0.1905)
			(layers "F.Cu" "F.Mask" "F.Paste")
			(net "GND")
			(options
				(clearance outline)
				(anchor circle)
			)
			(primitives
				(gr_poly
					(pts
						(arc
							(start -0.1778 0.5715)
							(mid -0.321484 0.511984)
							(end -0.381 0.3683)
						)
						(arc
							(start -0.381 -0.3683)
							(mid -0.321484 -0.511984)
							(end -0.1778 -0.5715)
						)
						(arc
							(start 0.1778 -0.5715)
							(mid 0.321484 -0.511984)
							(end 0.381 -0.3683)
						)
						(arc
							(start 0.381 0.3683)
							(mid 0.321484 0.511984)
							(end 0.1778 0.5715)
						)
					)
					(width 0)
					(fill yes)
				)
			)
		)
	)
	(footprint ""
		(layer "F.Cu")
		(at 45.44568 -121.868692 180)
		(property "Reference" "R91"
			(at 0 0 180)
			(layer "F.SilkS")
			(hide yes)
			(effects
				(font
					(size 1.27 1.27)
				)
			)
		)
		(property "Value" "300R2F-GP"
			(at 0.064008 -3.993896 180)
			(unlocked yes)
			(layer "F.Fab")
			(hide yes)
			(effects
				(font
					(size 1.016 1.016)
					(thickness 0.1524)
				)
			)
		)
		(property "Device Type" "R402H16"
			(at 0.064008 -5.517896 180)
			(unlocked yes)
			(layer "F.Fab")
			(hide yes)
			(effects
				(font
					(size 1.016 1.016)
					(thickness 0.1524)
				)
			)
		)
		(duplicate_pad_numbers_are_jumpers no)
		(fp_line
			(start 0.508 -0.9398)
			(end -0.508 -0.9398)
			(stroke
				(width 0.1524)
				(type default)
			)
			(layer "F.SilkS")
		)
		(fp_line
			(start -0.508 -0.9398)
			(end -0.508 0.9398)
			(stroke
				(width 0.1524)
				(type default)
			)
			(layer "F.SilkS")
		)
		(fp_rect
			(start -0.508 0.9398)
			(end 0.508 -0.9398)
			(stroke
				(width 0)
				(type default)
			)
			(fill no)
			(layer "F.CrtYd")
		)
		(fp_rect
			(start -0.508 0.9398)
			(end 0.508 -0.9398)
			(stroke
				(width 0)
				(type default)
			)
			(fill no)
			(layer "F.Fab")
		)
		(pad "1" smd custom
			(at 0 -0.4445 180)
			(size 0.1397 0.1397)
			(layers "F.Cu" "F.Mask" "F.Paste")
			(net "GND")
			(options
				(clearance outline)
				(anchor circle)
			)
			(primitives
				(gr_poly
					(pts
						(arc
							(start -0.1778 -0.2794)
							(mid -0.249642 -0.249642)
							(end -0.2794 -0.1778)
						)
						(arc
							(start -0.2794 0.1778)
							(mid -0.249642 0.249642)
							(end -0.1778 0.2794)
						)
						(arc
							(start 0.1778 0.2794)
							(mid 0.249642 0.249642)
							(end 0.2794 0.1778)
						)
						(arc
							(start 0.2794 -0.1778)
							(mid 0.249642 -0.249642)
							(end 0.1778 -0.2794)
						)
					)
					(width 0)
					(fill yes)
				)
			)
		)
		(pad "2" smd custom
			(at 0 0.4445 180)
			(size 0.1397 0.1397)
			(layers "F.Cu" "F.Mask" "F.Paste")
			(net "BMC_CPU_DIS")
			(options
				(clearance outline)
				(anchor circle)
			)
			(primitives
				(gr_poly
					(pts
						(arc
							(start -0.1778 -0.2794)
							(mid -0.249642 -0.249642)
							(end -0.2794 -0.1778)
						)
						(arc
							(start -0.2794 0.1778)
							(mid -0.249642 0.249642)
							(end -0.1778 0.2794)
						)
						(arc
							(start 0.1778 0.2794)
							(mid 0.249642 0.249642)
							(end 0.2794 0.1778)
						)
						(arc
							(start 0.2794 -0.1778)
							(mid 0.249642 -0.249642)
							(end 0.1778 -0.2794)
						)
					)
					(width 0)
					(fill yes)
				)
			)
		)
	)
	(footprint ""
		(layer "F.Cu")
		(at 16.041116 -162.5473 -90)
		(property "Reference" "R530"
			(at 0 0 270)
			(layer "F.SilkS")
			(hide yes)
			(effects
				(font
					(size 1.27 1.27)
				)
			)
		)
		(property "Value" "2K49R2F-GP"
			(at 0.064008 -3.993896 270)
			(unlocked yes)
			(layer "F.Fab")
			(hide yes)
			(effects
				(font
					(size 1.016 1.016)
					(thickness 0.1524)
				)
			)
		)
		(property "Device Type" "R402H16"
			(at 0.064008 -5.517896 270)
			(unlocked yes)
			(layer "F.Fab")
			(hide yes)
			(effects
				(font
					(size 1.016 1.016)
					(thickness 0.1524)
				)
			)
		)
		(duplicate_pad_numbers_are_jumpers no)
		(fp_line
			(start -0.508 -0.9398)
			(end -0.508 0.9398)
			(stroke
				(width 0.1524)
				(type default)
			)
			(layer "F.SilkS")
		)
		(fp_line
			(start 0.508 -0.9398)
			(end -0.508 -0.9398)
			(stroke
				(width 0.1524)
				(type default)
			)
			(layer "F.SilkS")
		)
		(fp_rect
			(start -0.508 0.9398)
			(end 0.508 -0.9398)
			(stroke
				(width 0)
				(type default)
			)
			(fill no)
			(layer "F.CrtYd")
		)
		(fp_rect
			(start -0.508 0.9398)
			(end 0.508 -0.9398)
			(stroke
				(width 0)
				(type default)
			)
			(fill no)
			(layer "F.Fab")
		)
		(pad "1" smd custom
			(at 0 -0.4445 270)
			(size 0.1397 0.1397)
			(layers "F.Cu" "F.Mask" "F.Paste")
			(net "TPS74801_P1V2_STBY_OUT")
			(options
				(clearance outline)
				(anchor circle)
			)
			(primitives
				(gr_poly
					(pts
						(arc
							(start -0.1778 -0.2794)
							(mid -0.249642 -0.249642)
							(end -0.2794 -0.1778)
						)
						(arc
							(start -0.2794 0.1778)
							(mid -0.249642 0.249642)
							(end -0.1778 0.2794)
						)
						(arc
							(start 0.1778 0.2794)
							(mid 0.249642 0.249642)
							(end 0.2794 0.1778)
						)
						(arc
							(start 0.2794 -0.1778)
							(mid 0.249642 -0.249642)
							(end 0.1778 -0.2794)
						)
					)
					(width 0)
					(fill yes)
				)
			)
		)
		(pad "2" smd custom
			(at 0 0.4445 270)
			(size 0.1397 0.1397)
			(layers "F.Cu" "F.Mask" "F.Paste")
			(net "TPS74801_P1V2_STBY_FB")
			(options
				(clearance outline)
				(anchor circle)
			)
			(primitives
				(gr_poly
					(pts
						(arc
							(start -0.1778 -0.2794)
							(mid -0.249642 -0.249642)
							(end -0.2794 -0.1778)
						)
						(arc
							(start -0.2794 0.1778)
							(mid -0.249642 0.249642)
							(end -0.1778 0.2794)
						)
						(arc
							(start 0.1778 0.2794)
							(mid 0.249642 0.249642)
							(end 0.2794 0.1778)
						)
						(arc
							(start 0.2794 -0.1778)
							(mid 0.249642 -0.249642)
							(end 0.1778 -0.2794)
						)
					)
					(width 0)
					(fill yes)
				)
			)
		)
	)
)
